# BASEBOARD_FAB2 (Tioga Pass) — schematic netlist excerpt (pin names and nets, part order shuffled) for the footprints in the layout excerpt that follows; sources: Cadence DE-HDL packaged netlist, KiCad conversion of Wiwynn_Tioga_Pass_MB.brd

J6E1  SCONN120_H61426002  CONN  pkg SM  page 194
  IOA1  = PVCCMCP_CPU0
  IOA2  = PVCCMCP_CPU0
  IOA3  = PVCCMCP_CPU0
  IOA4  = VSENSE_PVCCMCP_CPU0_SKT_VSEN
  IOA5  = PVCCMCP_CPU0
  IOA6  = PVCCMCP_CPU0
  IOA7  = PVCCMCP_CPU0
  IOA8  = PVCCMCP_CPU0
  IOA9  = PVCCMCP_CPU0
  IOA10  = PVCCMCP_CPU0
  IOA11  = PVCCMCP_CPU0
  IOA12  = PVCCMCP_CPU0
  IOA13  = PVCCMCP_CPU0
  IOA14  = PVCCMCP_CPU0
  IOA15  = PVCCMCP_CPU0
  IOA16  = PVCCMCP_CPU0
  IOA17  = PVCCMCP_CPU0
  IOA18  = PVCCMCP_CPU0
  IOA19  = GND
  IOA20  = GND
  IOB1  = PVCCMCP_CPU0
  IOB2  = PVCCMCP_CPU0
  IOB3  = PVCCMCP_CPU0
  IOB4  = VSENSE_PVCCMCP_CPU0_SKT_VRTN
  IOB5  = PVCCMCP_CPU0
  IOB6  = PVCCMCP_CPU0
  IOB7  = PVCCMCP_CPU0
  IOB8  = PVCCMCP_CPU0
  IOB9  = PVCCMCP_CPU0
  IOB10  = PVCCMCP_CPU0
  IOB11  = PVCCMCP_CPU0
  IOB12  = PVCCMCP_CPU0
  IOB13  = PVCCMCP_CPU0
  IOB14  = PVCCMCP_CPU0
  IOB15  = PVCCMCP_CPU0
  IOB16  = PVCCMCP_CPU0
  IOB17  = PVCCMCP_CPU0
  IOB18  = PVCCMCP_CPU0
  IOB19  = GND
  IOB20  = GND
  IOC1  = PVCCMCP_CPU0
  IOC2  = PVCCMCP_CPU0
  IOC3  = PVCCMCP_CPU0
  IOC4  = PVCCMCP_CPU0
  IOC5  = PVCCMCP_CPU0
  IOC6  = PVCCMCP_CPU0
  IOC7  = PVCCMCP_CPU0
  IOC8  = PVCCMCP_CPU0
  IOC9  = PVCCMCP_CPU0
  IOC10  = PVCCMCP_CPU0
  IOC11  = PVCCMCP_CPU0
  IOC12  = PVCCMCP_CPU0
  IOC13  = PVCCMCP_CPU0
  IOC14  = PVCCMCP_CPU0
  IOC15  = PVCCMCP_CPU0
  IOC16  = PVCCMCP_CPU0
  IOC17  = PVCCMCP_CPU0
  IOC18  = PVCCMCP_CPU0
  IOC19  = GND
  IOC20  = GND
  IOD1  = VSENSE_P1V8MCP_CPU0_SKT_VSEN
  IOD2  = VSENSE_P1V8MCP_CPU0_SKT_VRTN
  IOD3  = P1V8_MCP_CPU0
  IOD4  = GND
  IOD5  = GND
  IOD6  = GND
  IOD7  = GND
  IOD8  = GND
  IOD9  = GND
  IOD10  = GND
  IOD11  = GND
  IOD12  = GND
  IOD13  = GND
  IOD14  = GND
  IOD15  = GND
  IOD16  = GND
  IOD17  = GND
  IOD18  = GND
  IOD19  = GND
  IOD20  = GND
  IOE1  = P1V8_MCP_CPU0
  IOE2  = P1V8_MCP_CPU0
  IOE3  = P1V8_MCP_CPU0
  IOE4  = GND
  IOE5  = CLK_322M_156M_CPU0_OSC_VRM_DP
  IOE6  = GND
  IOE7  = GND
  IOE8  = GND
  IOE9  = GND
  IOE10  = GND
  IOE11  = GND
  IOE12  = GND
  IOE13  = GND
  IOE14  = GND
  IOE15  = GND
  IOE16  = GND
  IOE17  = GND
  IOE18  = GND
  IOE19  = GND
  IOE20  = GND
  IOF1  = P1V8_MCP_CPU0
  IOF2  = P1V8_MCP_CPU0
  IOF3  = P1V8_MCP_CPU0
  IOF4  = GND
  IOF5  = CLK_322M_156M_CPU0_OSC_VRM_DN
  IOF6  = GND
  IOF7  = GND
  IOF8  = GND
  IOF9  = GND
  IOF10  = GND
  IOF11  = GND
  IOF12  = GND
  IOF13  = GND
  IOF14  = GND
  IOF15  = GND
  IOF16  = GND
  IOF17  = GND
  IOF18  = GND
  IOF19  = GND
  IOF20  = GND

(kicad_pcb
	(version 20260206)
	(generator "pcbnew")
	(generator_version "10.0")
	(general
		(thickness 1.6)
		(legacy_teardrops no)
	)
	(paper "A4")
	(title_block
		(title "Wiwynn_Tioga_Pass_MB.brd")
		(comment 1 "Tioga Pass / footprint 587 of 4770 (J6E1), pads 102-122 of 122")
	)
	(layers
		(0 "F.Cu" signal "TOP")
		(4 "In1.Cu" signal "L2GND")
		(6 "In2.Cu" signal "L3")
		(8 "In3.Cu" signal "L4GND")
		(10 "In4.Cu" signal "L5")
		(12 "In5.Cu" signal "L6GND")
		(14 "In6.Cu" signal "L7VCC")
		(16 "In7.Cu" signal "L8VCC")
		(18 "In8.Cu" signal "L9GND")
		(20 "In9.Cu" signal "L10")
		(22 "In10.Cu" signal "L11GND")
		(24 "In11.Cu" signal "L12")
		(26 "In12.Cu" signal "L13GND")
		(2 "B.Cu" signal "BOTTOM")
		(9 "F.Adhes" user "F.Adhesive")
		(11 "B.Adhes" user "B.Adhesive")
		(13 "F.Paste" user "Package Geometry/Pastemask Top")
		(15 "B.Paste" user "Package Geometry/Pastemask Bottom")
		(5 "F.SilkS" user "Ref Des/Silkscreen Top")
		(7 "B.SilkS" user "Ref Des/Silkscreen Bottom")
		(1 "F.Mask" user "Board Geometry/Soldermask Top")
		(3 "B.Mask" user "Board Geometry/Soldermask Bottom")
		(17 "Dwgs.User" user "User.Drawings")
		(19 "Cmts.User" user "User.Comments")
		(21 "Eco1.User" user "User.Eco1")
		(23 "Eco2.User" user "User.Eco2")
		(25 "Edge.Cuts" user "Board Geometry/Outline")
		(27 "Margin" user)
		(31 "F.CrtYd" user "Package Geometry/Place Bound Top")
		(29 "B.CrtYd" user "Package Geometry/Place Bound Bottom")
		(35 "F.Fab" user "Ref Des/Assembly Top")
		(33 "B.Fab" user "Ref Des/Assembly Bottom")
	)
	(footprint ""
		(layer "F.Cu")
		(at 329.594972 -43.80103 90)
		(property "Reference" "J6E1"
			(at -3.59283 -5.018024 90)
			(unlocked yes)
			(layer "F.SilkS")
			(effects
				(font
					(size 0.7874 0.5842)
					(thickness 0.1524)
				)
			)
		)
		(property "Value" ""
			(at 0 0 90)
			(layer "F.Fab")
			(effects
				(font
					(size 1.27 1.27)
				)
			)
		)
		(duplicate_pad_numbers_are_jumpers no)
		(pad "E20" smd circle
			(at -5.08 24.13 90)
			(size 0.635 0.635)
			(layers "F.Cu" "F.Mask" "F.Paste")
			(net "GND")
		)
		(pad "F1" smd circle
			(at -6.35 0 90)
			(size 0.635 0.635)
			(layers "F.Cu" "F.Mask" "F.Paste")
			(net "P1V8_MCP_CPU0")
		)
		(pad "F2" smd circle
			(at -6.35 1.27 90)
			(size 0.635 0.635)
			(layers "F.Cu" "F.Mask" "F.Paste")
			(net "P1V8_MCP_CPU0")
		)
		(pad "F3" smd circle
			(at -6.35 2.54 90)
			(size 0.635 0.635)
			(layers "F.Cu" "F.Mask" "F.Paste")
			(net "P1V8_MCP_CPU0")
		)
		(pad "F4" smd circle
			(at -6.35 3.81 90)
			(size 0.635 0.635)
			(layers "F.Cu" "F.Mask" "F.Paste")
			(net "GND")
		)
		(pad "F5" smd circle
			(at -6.35 5.08 90)
			(size 0.635 0.635)
			(layers "F.Cu" "F.Mask" "F.Paste")
			(net "CLK_322M_156M_CPU0_OSC_VRM_DN")
		)
		(pad "F6" smd circle
			(at -6.35 6.35 90)
			(size 0.635 0.635)
			(layers "F.Cu" "F.Mask" "F.Paste")
			(net "GND")
		)
		(pad "F7" smd circle
			(at -6.35 7.62 90)
			(size 0.635 0.635)
			(layers "F.Cu" "F.Mask" "F.Paste")
			(net "GND")
		)
		(pad "F8" smd circle
			(at -6.35 8.89 90)
			(size 0.635 0.635)
			(layers "F.Cu" "F.Mask" "F.Paste")
			(net "GND")
		)
		(pad "F9" smd circle
			(at -6.35 10.16 90)
			(size 0.635 0.635)
			(layers "F.Cu" "F.Mask" "F.Paste")
			(net "GND")
		)
		(pad "F10" smd circle
			(at -6.35 11.43 90)
			(size 0.635 0.635)
			(layers "F.Cu" "F.Mask" "F.Paste")
			(net "GND")
		)
		(pad "F11" smd circle
			(at -6.35 12.7 90)
			(size 0.635 0.635)
			(layers "F.Cu" "F.Mask" "F.Paste")
			(net "GND")
		)
		(pad "F12" smd circle
			(at -6.35 13.97 90)
			(size 0.635 0.635)
			(layers "F.Cu" "F.Mask" "F.Paste")
			(net "GND")
		)
		(pad "F13" smd circle
			(at -6.35 15.24 90)
			(size 0.635 0.635)
			(layers "F.Cu" "F.Mask" "F.Paste")
			(net "GND")
		)
		(pad "F14" smd circle
			(at -6.35 16.51 90)
			(size 0.635 0.635)
			(layers "F.Cu" "F.Mask" "F.Paste")
			(net "GND")
		)
		(pad "F15" smd circle
			(at -6.35 17.78 90)
			(size 0.635 0.635)
			(layers "F.Cu" "F.Mask" "F.Paste")
			(net "GND")
		)
		(pad "F16" smd circle
			(at -6.35 19.05 90)
			(size 0.635 0.635)
			(layers "F.Cu" "F.Mask" "F.Paste")
			(net "GND")
		)
		(pad "F17" smd circle
			(at -6.35 20.32 90)
			(size 0.635 0.635)
			(layers "F.Cu" "F.Mask" "F.Paste")
			(net "GND")
		)
		(pad "F18" smd circle
			(at -6.35 21.59 90)
			(size 0.635 0.635)
			(layers "F.Cu" "F.Mask" "F.Paste")
			(net "GND")
		)
		(pad "F19" smd circle
			(at -6.35 22.86 90)
			(size 0.635 0.635)
			(layers "F.Cu" "F.Mask" "F.Paste")
			(net "GND")
		)
		(pad "F20" smd circle
			(at -6.35 24.13 90)
			(size 0.635 0.635)
			(layers "F.Cu" "F.Mask" "F.Paste")
			(net "GND")
		)
	)
)
